# SCM (Grand Teton) — schematic netlist excerpt (pin names and nets, part order shuffled) for the footprints in the layout excerpt that follows; sources: Cadence DE-HDL packaged netlist, KiCad conversion of 12092022_DA0F0TMDCD0_F0T_Management_Board_D_brd_V3_OCP.brd

PL29  Q_INDUCTOR  BLM18SN220TN1D/8000MA IND  pkg SMLF  page 55 : \1\ = P12V_AUX ; \2\ = SW_P1V2_AUX_FLT
D15  Q_LED  IC  pkg THLF  page 49 : A = HDD_LED_P5V_AUX ; C = HDD_LED_BUF_R

(kicad_pcb
	(version 20260206)
	(generator "pcbnew")
	(generator_version "10.0")
	(general
		(thickness 1.6)
		(legacy_teardrops no)
	)
	(paper "A4")
	(title_block
		(title "12092022_DA0F0TMDCD0_F0T_Management_Board_D_brd_V3_OCP.brd")
		(comment 1 "Grand Teton / footprints 537-538 of 1440")
	)
	(layers
		(0 "F.Cu" signal "TOP")
		(4 "In1.Cu" signal "GND")
		(6 "In2.Cu" signal "IN1")
		(8 "In3.Cu" signal "GND1")
		(10 "In4.Cu" signal "IN2")
		(12 "In5.Cu" signal "VCC")
		(14 "In6.Cu" signal "VCC1")
		(16 "In7.Cu" signal "IN3")
		(18 "In8.Cu" signal "GND2")
		(20 "In9.Cu" signal "IN4")
		(22 "In10.Cu" signal "GND3")
		(2 "B.Cu" signal "BOTTOM")
		(9 "F.Adhes" user "F.Adhesive")
		(11 "B.Adhes" user "B.Adhesive")
		(13 "F.Paste" user "Package Geometry/Pastemask Top")
		(15 "B.Paste" user "Package Geometry/Pastemask Bottom")
		(5 "F.SilkS" user "Ref Des/Silkscreen Top")
		(7 "B.SilkS" user "Ref Des/Silkscreen Bottom")
		(1 "F.Mask" user "Board Geometry/Soldermask Top")
		(3 "B.Mask" user "Board Geometry/Soldermask Bottom")
		(17 "Dwgs.User" user "User.Drawings")
		(19 "Cmts.User" user "User.Comments")
		(21 "Eco1.User" user "User.Eco1")
		(23 "Eco2.User" user "User.Eco2")
		(25 "Edge.Cuts" user "Board Geometry/Outline")
		(27 "Margin" user)
		(31 "F.CrtYd" user "Package Geometry/Place Bound Top")
		(29 "B.CrtYd" user "Package Geometry/Place Bound Bottom")
		(35 "F.Fab" user "Ref Des/Assembly Top")
		(33 "B.Fab" user "Ref Des/Assembly Bottom")
	)
	(footprint ""
		(layer "F.Cu")
		(at 82.804 -80.518 -90)
		(property "Reference" "PL29"
			(at 0 0 270)
			(layer "F.SilkS")
			(hide yes)
			(effects
				(font
					(size 1.27 1.27)
				)
			)
		)
		(property "Value" ""
			(at 0 0 270)
			(layer "F.Fab")
			(effects
				(font
					(size 1.27 1.27)
				)
			)
		)
		(duplicate_pad_numbers_are_jumpers no)
		(fp_line
			(start -1.27 0.5842)
			(end -1.27 -0.5842)
			(stroke
				(width 0.1524)
				(type default)
			)
			(layer "F.SilkS")
		)
		(fp_line
			(start -0.127 0.5842)
			(end -0.127 -0.5842)
			(stroke
				(width 0.1524)
				(type default)
			)
			(layer "F.SilkS")
		)
		(fp_line
			(start 0.127 0.5842)
			(end 0.127 -0.5842)
			(stroke
				(width 0.1524)
				(type default)
			)
			(layer "F.SilkS")
		)
		(fp_line
			(start 1.27 0.5842)
			(end -1.27 0.5842)
			(stroke
				(width 0.1524)
				(type default)
			)
			(layer "F.SilkS")
		)
		(fp_line
			(start 1.27 0.5842)
			(end 1.27 -0.5842)
			(stroke
				(width 0.1524)
				(type default)
			)
			(layer "F.SilkS")
		)
		(fp_line
			(start -1.27 -0.5588)
			(end -1.27 -0.5842)
			(stroke
				(width 0.1524)
				(type default)
			)
			(layer "F.SilkS")
		)
		(fp_line
			(start -1.27 -0.5842)
			(end 1.27 -0.5842)
			(stroke
				(width 0.1524)
				(type default)
			)
			(layer "F.SilkS")
		)
		(fp_line
			(start -0.9144 0.508)
			(end -0.9144 0.406654)
			(stroke
				(width 0.1)
				(type default)
			)
			(layer "F.Fab")
		)
		(fp_line
			(start 0.9144 0.508)
			(end -0.9144 0.508)
			(stroke
				(width 0.1)
				(type default)
			)
			(layer "F.Fab")
		)
		(fp_line
			(start -1.194308 0.406654)
			(end -1.194308 -0.406654)
			(stroke
				(width 0.1)
				(type default)
			)
			(layer "F.Fab")
		)
		(fp_line
			(start -0.9144 0.406654)
			(end -1.194308 0.406654)
			(stroke
				(width 0.1)
				(type default)
			)
			(layer "F.Fab")
		)
		(fp_line
			(start 0.9144 0.4064)
			(end 0.9144 0.508)
			(stroke
				(width 0.1)
				(type default)
			)
			(layer "F.Fab")
		)
		(fp_line
			(start 1.1938 0.4064)
			(end 0.9144 0.4064)
			(stroke
				(width 0.1)
				(type default)
			)
			(layer "F.Fab")
		)
		(fp_line
			(start -1.194308 -0.406654)
			(end -0.9144 -0.406654)
			(stroke
				(width 0.1)
				(type default)
			)
			(layer "F.Fab")
		)
		(fp_line
			(start -0.9144 -0.406654)
			(end -0.9144 -0.508)
			(stroke
				(width 0.1)
				(type default)
			)
			(layer "F.Fab")
		)
		(fp_line
			(start 0.9144 -0.406654)
			(end 1.1938 -0.406654)
			(stroke
				(width 0.1)
				(type default)
			)
			(layer "F.Fab")
		)
		(fp_line
			(start 1.1938 -0.406654)
			(end 1.1938 0.4064)
			(stroke
				(width 0.1)
				(type default)
			)
			(layer "F.Fab")
		)
		(fp_line
			(start -0.9144 -0.508)
			(end 0.9144 -0.508)
			(stroke
				(width 0.1)
				(type default)
			)
			(layer "F.Fab")
		)
		(fp_line
			(start 0.9144 -0.508)
			(end 0.9144 -0.406654)
			(stroke
				(width 0.1)
				(type default)
			)
			(layer "F.Fab")
		)
		(pad "1" smd rect
			(at -0.7366 0 180)
			(size 0.7112 0.8128)
			(layers "F.Cu" "F.Mask" "F.Paste")
			(net "P12V_AUX")
		)
		(pad "2" smd rect
			(at 0.7366 0 180)
			(size 0.7112 0.8128)
			(layers "F.Cu" "F.Mask" "F.Paste")
			(net "SW_P1V2_AUX_FLT")
		)
	)
	(footprint ""
		(layer "F.Cu")
		(at 22.979888 -6.290056)
		(property "Reference" "D15"
			(at -1.135888 -2.547874 0)
			(unlocked yes)
			(layer "F.SilkS")
			(effects
				(font
					(size 0.7874 0.5842)
					(thickness 0.1524)
				)
				(justify left)
			)
		)
		(property "Value" ""
			(at 0 0 0)
			(layer "F.Fab")
			(effects
				(font
					(size 1.27 1.27)
				)
			)
		)
		(duplicate_pad_numbers_are_jumpers no)
		(fp_line
			(start -1.080008 -1.999996)
			(end 3.620008 -1.999996)
			(stroke
				(width 0.1524)
				(type default)
			)
			(layer "F.SilkS")
		)
		(fp_line
			(start -1.080008 3.999992)
			(end -1.080008 -1.999996)
			(stroke
				(width 0.1524)
				(type default)
			)
			(layer "F.SilkS")
		)
		(fp_line
			(start -0.230124 3.999992)
			(end -1.080008 3.999992)
			(stroke
				(width 0.1524)
				(type default)
			)
			(layer "F.SilkS")
		)
		(fp_line
			(start -0.230124 5.199888)
			(end -0.230124 3.999992)
			(stroke
				(width 0.1524)
				(type default)
			)
			(layer "F.SilkS")
		)
		(fp_line
			(start 2.770124 3.999992)
			(end 2.770124 5.199888)
			(stroke
				(width 0.1524)
				(type default)
			)
			(layer "F.SilkS")
		)
		(fp_line
			(start 3.620008 -1.999996)
			(end 3.620008 3.999992)
			(stroke
				(width 0.1524)
				(type default)
			)
			(layer "F.SilkS")
		)
		(fp_line
			(start 3.620008 3.999992)
			(end 2.770124 3.999992)
			(stroke
				(width 0.1524)
				(type default)
			)
			(layer "F.SilkS")
		)
		(fp_arc
			(start 1.27 6.700012)
			(mid 0.209252 6.260636)
			(end -0.230124 5.199888)
			(stroke
				(width 0.1524)
				(type default)
			)
			(layer "F.SilkS")
		)
		(fp_arc
			(start 2.770124 5.199888)
			(mid 2.330748 6.260636)
			(end 1.27 6.700012)
			(stroke
				(width 0.1524)
				(type default)
			)
			(layer "F.SilkS")
		)
		(fp_line
			(start -1.080008 -1.999996)
			(end 3.620008 -1.999996)
			(stroke
				(width 0.1)
				(type default)
			)
			(layer "F.Fab")
		)
		(fp_line
			(start -1.080008 3.999992)
			(end -1.080008 -1.999996)
			(stroke
				(width 0.1)
				(type default)
			)
			(layer "F.Fab")
		)
		(fp_line
			(start -0.230124 3.999992)
			(end -1.080008 3.999992)
			(stroke
				(width 0.1)
				(type default)
			)
			(layer "F.Fab")
		)
		(fp_line
			(start -0.230124 5.199888)
			(end -0.230124 3.999992)
			(stroke
				(width 0.1)
				(type default)
			)
			(layer "F.Fab")
		)
		(fp_line
			(start 2.770124 3.999992)
			(end 2.770124 5.199888)
			(stroke
				(width 0.1)
				(type default)
			)
			(layer "F.Fab")
		)
		(fp_line
			(start 3.620008 -1.999996)
			(end 3.620008 3.999992)
			(stroke
				(width 0.1)
				(type default)
			)
			(layer "F.Fab")
		)
		(fp_line
			(start 3.620008 3.999992)
			(end 2.770124 3.999992)
			(stroke
				(width 0.1)
				(type default)
			)
			(layer "F.Fab")
		)
		(fp_arc
			(start 1.27 6.700012)
			(mid 0.209252 6.260636)
			(end -0.230124 5.199888)
			(stroke
				(width 0.1)
				(type default)
			)
			(layer "F.Fab")
		)
		(fp_arc
			(start 2.770124 5.199888)
			(mid 2.330748 6.260636)
			(end 1.27 6.700012)
			(stroke
				(width 0.1)
				(type default)
			)
			(layer "F.Fab")
		)
		(pad "A" thru_hole rect
			(at 0 0)
			(size 1.2192 1.2192)
			(drill 0.8128)
			(layers "*.Cu" "*.Mask")
			(remove_unused_layers no)
			(net "HDD_LED_P5V_AUX")
			(clearance 0.0508)
			(thermal_gap 0.0508)
			(padstack
				(mode front_inner_back)
				(layer "Inner"
					(shape circle)
					(size 1.2192 1.2192)
					(clearance 0.0508)
				)
				(layer "B.Cu"
					(shape rect)
					(size 1.2192 1.2192)
					(clearance 0.0508)
				)
			)
		)
		(pad "C" thru_hole circle
			(at 2.54 0)
			(size 1.2192 1.2192)
			(drill 0.8128)
			(layers "*.Cu" "*.Mask")
			(remove_unused_layers no)
			(net "HDD_LED_BUF_R")
			(clearance 0.0508)
			(thermal_gap 0.0508)
		)
	)
)
